# S9S_MB_2U (Grand Teton) — schematic netlist excerpt (pin names and nets, part order shuffled) for the footprints in the layout excerpt that follows; sources: Cadence DE-HDL packaged netlist, KiCad conversion of 03242023_DA0F0TMBIJ0_F0T_Motherboard_J_brd_V01_OCP.brd

J11  SCONN288_ADR50017P130CC  SCONN288_ADR50017-P130CC IO  pkg DDR288S_1-1VXB  page 92
  VIN_BULK0  = P12V_S3_AUX_CPU0_NVDIMM
  RFU0  = TP_CHF_CPU0_DIMM1_FRU_0
  VIN_MGMT  = P3V3_AUX
  HSCL  = I3C_SPD_DDREFGH_CPU0_LVC1_SCL_2
  HSDA  = I3C_SPD_DDREFGH_CPU0_LVC1_SDA
  VSS0  = GND
  DQ0_A  = M_F_CPU0_SA_DQ<0>
  VSS1  = GND
  DQ1_A  = M_F_CPU0_SA_DQ<1>
  VSS2  = GND
  DQS0_A_T  = M_F_CPU0_SA_DQS_DP<0>
  DQS0_A_C  = M_F_CPU0_SA_DQS_DN<0>
  VSS3  = GND
  DQ4_A  = M_F_CPU0_SA_DQ<4>
  VSS4  = GND
  DQ5_A  = M_F_CPU0_SA_DQ<5>
  VSS5  = GND
  DQ8_A  = M_F_CPU0_SA_DQ<8>
  VSS6  = GND
  DQ9_A  = M_F_CPU0_SA_DQ<9>
  VSS7  = GND
  DQS1_A_T  = M_F_CPU0_SA_DQS_DP<1>
  DQS1_A_C  = M_F_CPU0_SA_DQS_DN<1>
  VSS8  = GND
  DQ12_A  = M_F_CPU0_SA_DQ<12>
  VSS9  = GND
  DQ13_A  = M_F_CPU0_SA_DQ<13>
  VSS10  = GND
  DQ16_A  = M_F_CPU0_SA_DQ<16>
  VSS11  = GND
  DQ17_A  = M_F_CPU0_SA_DQ<17>
  VSS12  = GND
  DQS2_A_T  = M_F_CPU0_SA_DQS_DP<2>
  DQS2_A_C  = M_F_CPU0_SA_DQS_DN<2>
  VSS13  = GND
  DQ20_A  = M_F_CPU0_SA_DQ<20>
  VSS14  = GND
  DQ21_A  = M_F_CPU0_SA_DQ<21>
  VSS15  = GND
  DQ24_A  = M_F_CPU0_SA_DQ<24>
  VSS16  = GND
  DQ25_A  = M_F_CPU0_SA_DQ<25>
  VSS17  = GND
  DQS3_A_T  = M_F_CPU0_SA_DQS_DP<3>
  DQS3_A_C  = M_F_CPU0_SA_DQS_DN<3>
  VSS18  = GND
  DQ28_A  = M_F_CPU0_SA_DQ<28>
  VSS19  = GND
  DQ29_A  = M_F_CPU0_SA_DQ<29>
  VSS20  = GND
  CB0_A  = M_F_CPU0_SA_CB<0>
  VSS21  = GND
  CB1_A  = M_F_CPU0_SA_CB<1>
  VSS22  = GND
  DQS4_A_T  = M_F_CPU0_SA_DQS_DP<4>
  DQS4_A_C  = M_F_CPU0_SA_DQS_DN<4>
  VSS23  = GND
  CB4_A  = M_F_CPU0_SA_CB<4>
  VSS24  = GND
  CB5_A  = M_F_CPU0_SA_CB<5>
  VSS25  = GND
  ALERT_N  = M_F_CPU0_ALERT_N
  VSS26  = GND
  CS0_A_N  = M_F_CPU0_SA_CS_N<0>
  VSS27  = GND
  CA0_A  = M_F_CPU0_SA_CA<0>
  VSS28  = GND
  CA2_A  = M_F_CPU0_SA_CA<2>
  VSS29  = GND
  CA4_A  = M_F_CPU0_SA_CA<4>
  VSS30  = GND
  CA6_A  = M_F_CPU0_SA_CA<6>
  VSS31  = GND
  PAR_A  = M_F_CPU0_SA_PAR
  VSS32  = GND
  CA0_B  = M_F_CPU0_SB_CA<0>
  VSS33  = GND
  CA2_B  = M_F_CPU0_SB_CA<2>
  VSS34  = GND
  CA4_B  = M_F_CPU0_SB_CA<4>
  VSS35  = GND
  CA6_B  = M_F_CPU0_SB_CA<6>
  VSS36  = GND
  CS0_B_N  = M_F_CPU0_SB_CS_N<0>
  VSS37  = GND
  \lbd||rsp_a_n\  = M_F_CPU0_SA_RSP<0>
  \lbs||rsp_b_n\  = M_F_CPU0_SB_RSP<0>
  VSS38  = GND
  CB4_B  = M_F_CPU0_SB_CB<4>
  VSS39  = GND
  CB5_B  = M_F_CPU0_SB_CB<5>
  VSS40  = GND
  \dqs9_b_t||tdqs9_b_t||dbi4_b_n\  = M_F_CPU0_SB_DQS_DP<9>
  \dqs9_b_c||tdqs9_b_c\  = M_F_CPU0_SB_DQS_DN<9>
  VSS41  = GND
  CB0_B  = M_F_CPU0_SB_CB<0>
  VSS42  = GND
  CB1_B  = M_F_CPU0_SB_CB<1>
  VSS43  = GND
  DQ0_B  = M_F_CPU0_SB_DQ<0>
  VSS44  = GND
  DQ1_B  = M_F_CPU0_SB_DQ<1>
  VSS45  = GND
  DQS0_B_T  = M_F_CPU0_SB_DQS_DP<0>
  DQS0_B_C  = M_F_CPU0_SB_DQS_DN<0>
  VSS46  = GND
  DQ4_B  = M_F_CPU0_SB_DQ<4>
  VSS47  = GND
  DQ5_B  = M_F_CPU0_SB_DQ<5>
  VSS48  = GND
  DQ8_B  = M_F_CPU0_SB_DQ<8>
  VSS49  = GND
  DQ9_B  = M_F_CPU0_SB_DQ<9>
  VSS50  = GND
  DQS1_B_T  = M_F_CPU0_SB_DQS_DP<1>
  DQS1_B_C  = M_F_CPU0_SB_DQS_DN<1>
  VSS51  = GND
  DQ12_B  = M_F_CPU0_SB_DQ<12>
  VSS52  = GND
  DQ13_B  = M_F_CPU0_SB_DQ<13>
  VSS53  = GND
  DQ16_B  = M_F_CPU0_SB_DQ<16>
  VSS54  = GND
  DQ17_B  = M_F_CPU0_SB_DQ<17>
  VSS55  = GND
  DQS2_B_T  = M_F_CPU0_SB_DQS_DP<2>
  DQS2_B_C  = M_F_CPU0_SB_DQS_DN<2>
  VSS56  = GND
  DQ20_B  = M_F_CPU0_SB_DQ<20>
  VSS57  = GND
  DQ21_B  = M_F_CPU0_SB_DQ<21>
  VSS58  = GND
  DQ24_B  = M_F_CPU0_SB_DQ<24>
  VSS59  = GND
  DQ25_B  = M_F_CPU0_SB_DQ<25>
  VSS60  = GND
  DQS3_B_T  = M_F_CPU0_SB_DQS_DP<3>
  DQS3_B_C  = M_F_CPU0_SB_DQS_DN<3>
  VSS61  = GND
  DQ28_B  = M_F_CPU0_SB_DQ<28>
  VSS62  = GND
  DQ29_B  = M_F_CPU0_SB_DQ<29>
  VSS63  = GND
  RFU1  = TP_CHF_CPU0_DIMM1_FRU_1
  VIN_BULK1  = P12V_S3_AUX_CPU0_NVDIMM
  VIN_BULK2  = P12V_S3_AUX_CPU0_NVDIMM
  \pwr_good||fail_n\  = PWRGD_CHF_CPU0_DIMM1
  HSA  = PD_CHF_CPU0_DIMM1_SAA
  RFU2  = TP_CHF_CPU0_DIMM1_FRU_2
  RFU3  = TP_CHF_CPU0_DIMM1_FRU_3
  VSS64  = GND
  DQ2_A  = M_F_CPU0_SA_DQ<2>
  VSS65  = GND
  DQ3_A  = M_F_CPU0_SA_DQ<3>
  VSS66  = GND
  \dqs5_a_c||tdqs5_a_c||dqs5_a_t||tdqs5_a_t\  = M_F_CPU0_SA_DQS_DN<5>
  \dqs5_a_t||tdqs5_a_t\  = M_F_CPU0_SA_DQS_DP<5>
  VSS67  = GND
  DQ6_A  = M_F_CPU0_SA_DQ<6>
  VSS68  = GND
  DQ7_A  = M_F_CPU0_SA_DQ<7>
  VSS69  = GND
  DQ10_A  = M_F_CPU0_SA_DQ<10>
  VSS70  = GND
  DQ11_A  = M_F_CPU0_SA_DQ<11>
  VSS71  = GND
  \dqs6_a_c||tdqs6_a_c||dqs6_a_t||tdqs6_a_t\  = M_F_CPU0_SA_DQS_DN<6>
  \dqs6_a_t||tdqs6_a_t\  = M_F_CPU0_SA_DQS_DP<6>
  VSS72  = GND
  DQ14_A  = M_F_CPU0_SA_DQ<14>
  VSS73  = GND
  DQ15_A  = M_F_CPU0_SA_DQ<15>
  VSS74  = GND
  DQ18_A  = M_F_CPU0_SA_DQ<18>
  VSS75  = GND
  DQ19_A  = M_F_CPU0_SA_DQ<19>
  VSS76  = GND
  \dqs7_a_c||tdqs7_a_c\  = M_F_CPU0_SA_DQS_DN<7>
  \dqs7_a_t||tdqs7_a_t\  = M_F_CPU0_SA_DQS_DP<7>
  VSS77  = GND
  DQ22_A  = M_F_CPU0_SA_DQ<22>
  VSS78  = GND
  DQ23_A  = M_F_CPU0_SA_DQ<23>
  VSS79  = GND
  DQ26_A  = M_F_CPU0_SA_DQ<26>
  VSS80  = GND
  DQ27_A  = M_F_CPU0_SA_DQ<27>
  VSS81  = GND
  \dqs8_a_c||tdqs8_a_c\  = M_F_CPU0_SA_DQS_DN<8>
  \dqs8_a_t||tdqs8_a_t\  = M_F_CPU0_SA_DQS_DP<8>
  VSS82  = GND
  DQ30_A  = M_F_CPU0_SA_DQ<30>
  VSS83  = GND
  DQ31_A  = M_F_CPU0_SA_DQ<31>
  VSS84  = GND
  CB2_A  = M_F_CPU0_SA_CB<2>
  VSS85  = GND
  CB3_A  = M_F_CPU0_SA_CB<3>
  VSS86  = GND
  \dqs9_a_c||tdqs9_a_c\  = M_F_CPU0_SA_DQS_DN<9>
  \dqs9_a_t||tdqs9_a_t\  = M_F_CPU0_SA_DQS_DP<9>
  VSS87  = GND
  CB6_A  = M_F_CPU0_SA_CB<6>
  VSS88  = GND
  CB7_A  = M_F_CPU0_SA_CB<7>
  VSS89  = GND
  RESET_N  = RST_M_EF_CPU0_FPGA_N
  VSS90  = GND
  CS1_A_N  = M_F_CPU0_SA_CS_N<1>
  VSS91  = GND
  CA1_A  = M_F_CPU0_SA_CA<1>
  VSS92  = GND
  CA3_A  = M_F_CPU0_SA_CA<3>
  VSS93  = GND
  CA5_A  = M_F_CPU0_SA_CA<5>
  VSS94  = GND
  CK_T  = M_F_CPU0_CLK_DP<0>
  CK_C  = M_F_CPU0_CLK_DN<0>
  VSS95  = GND
  RFU4  = TP_CHF_CPU0_DIMM1_FRU_4
  CA1_B  = M_F_CPU0_SB_CA<1>
  VSS96  = GND
  CA3_B  = M_F_CPU0_SB_CA<3>
  VSS97  = GND
  CA5_B  = M_F_CPU0_SB_CA<5>
  VSS98  = GND
  PAR_B  = M_F_CPU0_SB_PAR
  VSS99  = GND
  CS1_B_N  = M_F_CPU0_SB_CS_N<1>
  VSS100  = GND
  RFU5  = TP_CHF_CPU0_DIMM1_FRU_5
  RFU6  = TP_CHF_CPU0_DIMM1_FRU_6
  VSS101  = GND
  CB6_B  = M_F_CPU0_SB_CB<6>
  VSS102  = GND
  CB7_B  = M_F_CPU0_SB_CB<7>
  VSS103  = GND
  DQS4_B_C  = M_F_CPU0_SB_DQS_DN<4>
  DQS4_B_T  = M_F_CPU0_SB_DQS_DP<4>
  VSS104  = GND
  CB2_B  = M_F_CPU0_SB_CB<2>
  VSS105  = GND
  CB3_B  = M_F_CPU0_SB_CB<3>
  VSS106  = GND
  DQ2_B  = M_F_CPU0_SB_DQ<2>
  VSS107  = GND
  DQ3_B  = M_F_CPU0_SB_DQ<3>
  VSS108  = GND
  \dqs5_b_c||tdqs5_b_c\  = M_F_CPU0_SB_DQS_DN<5>
  \dqs5_b_t||tdqs5_b_t\  = M_F_CPU0_SB_DQS_DP<5>
  VSS109  = GND
  DQ6_B  = M_F_CPU0_SB_DQ<6>
  VSS110  = GND
  DQ7_B  = M_F_CPU0_SB_DQ<7>
  VSS111  = GND
  DQ10_B  = M_F_CPU0_SB_DQ<10>
  VSS112  = GND
  DQ11_B  = M_F_CPU0_SB_DQ<11>
  VSS113  = GND
  \dqs6_b_c||tdqs6_b_c\  = M_F_CPU0_SB_DQS_DN<6>
  \dqs6_b_t||tdqs6_b_t\  = M_F_CPU0_SB_DQS_DP<6>
  VSS114  = GND
  DQ14_B  = M_F_CPU0_SB_DQ<14>
  VSS115  = GND
  DQ15_B  = M_F_CPU0_SB_DQ<15>
  VSS116  = GND
  DQ18_B  = M_F_CPU0_SB_DQ<18>
  VSS117  = GND
  DQ19_B  = M_F_CPU0_SB_DQ<19>
  VSS118  = GND
  \dqs7_b_c||tdqs7_b_c\  = M_F_CPU0_SB_DQS_DN<7>
  \dqs7_b_t||tdqs7_b_t\  = M_F_CPU0_SB_DQS_DP<7>
  VSS119  = GND
  DQ22_B  = M_F_CPU0_SB_DQ<22>
  VSS120  = GND
  DQ23_B  = M_F_CPU0_SB_DQ<23>
  VSS121  = GND
  DQ26_B  = M_F_CPU0_SB_DQ<26>
  VSS122  = GND
  DQ27_B  = M_F_CPU0_SB_DQ<27>
  VSS123  = GND
  \dqs8_b_c||tdqs8_b_c\  = M_F_CPU0_SB_DQS_DN<8>
  \dqs8_b_t||tdqs8_b_t\  = M_F_CPU0_SB_DQS_DP<8>
  VSS124  = GND
  DQ30_B  = M_F_CPU0_SB_DQ<30>
  VSS125  = GND
  DQ31_B  = M_F_CPU0_SB_DQ<31>
  VSS126  = GND
  G1  = GND
  G2  = GND
  G3  = GND

(kicad_pcb
	(version 20260206)
	(generator "pcbnew")
	(generator_version "10.0")
	(general
		(thickness 1.6)
		(legacy_teardrops no)
	)
	(paper "A4")
	(title_block
		(title "03242023_DA0F0TMBIJ0_F0T_Motherboard_J_brd_V01_OCP.brd")
		(comment 1 "Grand Teton / footprint 1952 of 6105 (J11), pads 46-91 of 291")
	)
	(layers
		(0 "F.Cu" signal "TOP")
		(4 "In1.Cu" signal "GND")
		(6 "In2.Cu" signal "IN1")
		(8 "In3.Cu" signal "GND1")
		(10 "In4.Cu" signal "IN2")
		(12 "In5.Cu" signal "GND2")
		(14 "In6.Cu" signal "IN3")
		(16 "In7.Cu" signal "GND3")
		(18 "In8.Cu" signal "VCC")
		(20 "In9.Cu" signal "VCC1")
		(22 "In10.Cu" signal "GND4")
		(24 "In11.Cu" signal "IN4")
		(26 "In12.Cu" signal "GND5")
		(28 "In13.Cu" signal "IN5")
		(30 "In14.Cu" signal "GND6")
		(32 "In15.Cu" signal "IN6")
		(34 "In16.Cu" signal "GND7")
		(2 "B.Cu" signal "BOTTOM")
		(9 "F.Adhes" user "F.Adhesive")
		(11 "B.Adhes" user "B.Adhesive")
		(13 "F.Paste" user "Package Geometry/Pastemask Top")
		(15 "B.Paste" user "Package Geometry/Pastemask Bottom")
		(5 "F.SilkS" user "Ref Des/Silkscreen Top")
		(7 "B.SilkS" user "Ref Des/Silkscreen Bottom")
		(1 "F.Mask" user "Board Geometry/Soldermask Top")
		(3 "B.Mask" user "Board Geometry/Soldermask Bottom")
		(17 "Dwgs.User" user "User.Drawings")
		(19 "Cmts.User" user "User.Comments")
		(21 "Eco1.User" user "User.Eco1")
		(23 "Eco2.User" user "User.Eco2")
		(25 "Edge.Cuts" user "Board Geometry/Outline")
		(27 "Margin" user)
		(31 "F.CrtYd" user "Package Geometry/Place Bound Top")
		(29 "B.CrtYd" user "Package Geometry/Place Bound Bottom")
		(35 "F.Fab" user "Ref Des/Assembly Top")
		(33 "B.Fab" user "Ref Des/Assembly Bottom")
	)
	(footprint ""
		(layer "F.Cu")
		(at 431.434748 -258.091686)
		(property "Reference" "J11"
			(at -3.683 -81.702148 0)
			(unlocked yes)
			(layer "F.SilkS")
			(effects
				(font
					(size 0.7874 0.5842)
					(thickness 0.1524)
				)
				(justify left)
			)
		)
		(property "Value" ""
			(at 0 0 0)
			(layer "F.Fab")
			(effects
				(font
					(size 1.27 1.27)
				)
			)
		)
		(duplicate_pad_numbers_are_jumpers no)
		(pad "46" smd rect
			(at -2.050034 -25.07488 270)
			(size 0.519938 1.4986)
			(layers "F.Cu" "F.Mask" "F.Paste")
			(net "GND")
		)
		(pad "47" smd rect
			(at -2.050034 -24.224996 270)
			(size 0.519938 1.4986)
			(layers "F.Cu" "F.Mask" "F.Paste")
			(net "M_F_CPU0_SA_DQ<28>")
		)
		(pad "48" smd rect
			(at -2.050034 -23.375112 270)
			(size 0.519938 1.4986)
			(layers "F.Cu" "F.Mask" "F.Paste")
			(net "GND")
		)
		(pad "49" smd rect
			(at -2.050034 -22.524974 270)
			(size 0.519938 1.4986)
			(layers "F.Cu" "F.Mask" "F.Paste")
			(net "M_F_CPU0_SA_DQ<29>")
		)
		(pad "50" smd rect
			(at -2.050034 -21.67509 270)
			(size 0.519938 1.4986)
			(layers "F.Cu" "F.Mask" "F.Paste")
			(net "GND")
		)
		(pad "51" smd rect
			(at -2.050034 -20.824952 270)
			(size 0.519938 1.4986)
			(layers "F.Cu" "F.Mask" "F.Paste")
			(net "M_F_CPU0_SA_CB<0>")
		)
		(pad "52" smd rect
			(at -2.050034 -19.975068 270)
			(size 0.519938 1.4986)
			(layers "F.Cu" "F.Mask" "F.Paste")
			(net "GND")
		)
		(pad "53" smd rect
			(at -2.050034 -19.12493 270)
			(size 0.519938 1.4986)
			(layers "F.Cu" "F.Mask" "F.Paste")
			(net "M_F_CPU0_SA_CB<1>")
		)
		(pad "54" smd rect
			(at -2.050034 -18.275046 270)
			(size 0.519938 1.4986)
			(layers "F.Cu" "F.Mask" "F.Paste")
			(net "GND")
		)
		(pad "55" smd rect
			(at -2.050034 -17.424908 270)
			(size 0.519938 1.4986)
			(layers "F.Cu" "F.Mask" "F.Paste")
			(net "M_F_CPU0_SA_DQS_DP<4>")
		)
		(pad "56" smd rect
			(at -2.050034 -16.575024 270)
			(size 0.519938 1.4986)
			(layers "F.Cu" "F.Mask" "F.Paste")
			(net "M_F_CPU0_SA_DQS_DN<4>")
		)
		(pad "57" smd rect
			(at -2.050034 -15.724886 270)
			(size 0.519938 1.4986)
			(layers "F.Cu" "F.Mask" "F.Paste")
			(net "GND")
		)
		(pad "58" smd rect
			(at -2.050034 -14.875002 270)
			(size 0.519938 1.4986)
			(layers "F.Cu" "F.Mask" "F.Paste")
			(net "M_F_CPU0_SA_CB<4>")
		)
		(pad "59" smd rect
			(at -2.050034 -14.025118 270)
			(size 0.519938 1.4986)
			(layers "F.Cu" "F.Mask" "F.Paste")
			(net "GND")
		)
		(pad "60" smd rect
			(at -2.050034 -13.17498 270)
			(size 0.519938 1.4986)
			(layers "F.Cu" "F.Mask" "F.Paste")
			(net "M_F_CPU0_SA_CB<5>")
		)
		(pad "61" smd rect
			(at -2.050034 -12.325096 270)
			(size 0.519938 1.4986)
			(layers "F.Cu" "F.Mask" "F.Paste")
			(net "GND")
		)
		(pad "62" smd rect
			(at -2.050034 -11.474958 270)
			(size 0.519938 1.4986)
			(layers "F.Cu" "F.Mask" "F.Paste")
			(net "M_F_CPU0_ALERT_N")
		)
		(pad "63" smd rect
			(at -2.050034 -10.625074 270)
			(size 0.519938 1.4986)
			(layers "F.Cu" "F.Mask" "F.Paste")
			(net "GND")
		)
		(pad "64" smd rect
			(at -2.050034 -9.774936 270)
			(size 0.519938 1.4986)
			(layers "F.Cu" "F.Mask" "F.Paste")
			(net "M_F_CPU0_SA_CS_N<0>")
		)
		(pad "65" smd rect
			(at -2.050034 -8.925052 270)
			(size 0.519938 1.4986)
			(layers "F.Cu" "F.Mask" "F.Paste")
			(net "GND")
		)
		(pad "66" smd rect
			(at -2.050034 -8.074914 270)
			(size 0.519938 1.4986)
			(layers "F.Cu" "F.Mask" "F.Paste")
			(net "M_F_CPU0_SA_CA<0>")
		)
		(pad "67" smd rect
			(at -2.050034 -7.22503 270)
			(size 0.519938 1.4986)
			(layers "F.Cu" "F.Mask" "F.Paste")
			(net "GND")
		)
		(pad "68" smd rect
			(at -2.050034 -6.374892 270)
			(size 0.519938 1.4986)
			(layers "F.Cu" "F.Mask" "F.Paste")
			(net "M_F_CPU0_SA_CA<2>")
		)
		(pad "69" smd rect
			(at -2.050034 -5.525008 270)
			(size 0.519938 1.4986)
			(layers "F.Cu" "F.Mask" "F.Paste")
			(net "GND")
		)
		(pad "70" smd rect
			(at -2.050034 -4.675124 270)
			(size 0.519938 1.4986)
			(layers "F.Cu" "F.Mask" "F.Paste")
			(net "M_F_CPU0_SA_CA<4>")
		)
		(pad "71" smd rect
			(at -2.050034 -3.824986 270)
			(size 0.519938 1.4986)
			(layers "F.Cu" "F.Mask" "F.Paste")
			(net "GND")
		)
		(pad "72" smd rect
			(at -2.050034 -2.975102 270)
			(size 0.519938 1.4986)
			(layers "F.Cu" "F.Mask" "F.Paste")
			(net "M_F_CPU0_SA_CA<6>")
		)
		(pad "73" smd rect
			(at -2.050034 -2.124964 270)
			(size 0.519938 1.4986)
			(layers "F.Cu" "F.Mask" "F.Paste")
			(net "GND")
		)
		(pad "74" smd rect
			(at -2.050034 -1.27508 270)
			(size 0.519938 1.4986)
			(layers "F.Cu" "F.Mask" "F.Paste")
			(net "M_F_CPU0_SA_PAR")
		)
		(pad "75" smd rect
			(at -2.050034 -0.424942 270)
			(size 0.519938 1.4986)
			(layers "F.Cu" "F.Mask" "F.Paste")
			(net "GND")
		)
		(pad "76" smd rect
			(at -2.050034 5.525008 270)
			(size 0.519938 1.4986)
			(layers "F.Cu" "F.Mask" "F.Paste")
			(net "M_F_CPU0_SB_CA<0>")
		)
		(pad "77" smd rect
			(at -2.050034 6.374892 270)
			(size 0.519938 1.4986)
			(layers "F.Cu" "F.Mask" "F.Paste")
			(net "GND")
		)
		(pad "78" smd rect
			(at -2.050034 7.22503 270)
			(size 0.519938 1.4986)
			(layers "F.Cu" "F.Mask" "F.Paste")
			(net "M_F_CPU0_SB_CA<2>")
		)
		(pad "79" smd rect
			(at -2.050034 8.074914 270)
			(size 0.519938 1.4986)
			(layers "F.Cu" "F.Mask" "F.Paste")
			(net "GND")
		)
		(pad "80" smd rect
			(at -2.050034 8.925052 270)
			(size 0.519938 1.4986)
			(layers "F.Cu" "F.Mask" "F.Paste")
			(net "M_F_CPU0_SB_CA<4>")
		)
		(pad "81" smd rect
			(at -2.050034 9.774936 270)
			(size 0.519938 1.4986)
			(layers "F.Cu" "F.Mask" "F.Paste")
			(net "GND")
		)
		(pad "82" smd rect
			(at -2.050034 10.625074 270)
			(size 0.519938 1.4986)
			(layers "F.Cu" "F.Mask" "F.Paste")
			(net "M_F_CPU0_SB_CA<6>")
		)
		(pad "83" smd rect
			(at -2.050034 11.474958 270)
			(size 0.519938 1.4986)
			(layers "F.Cu" "F.Mask" "F.Paste")
			(net "GND")
		)
		(pad "84" smd rect
			(at -2.050034 12.325096 270)
			(size 0.519938 1.4986)
			(layers "F.Cu" "F.Mask" "F.Paste")
			(net "M_F_CPU0_SB_CS_N<0>")
		)
		(pad "85" smd rect
			(at -2.050034 13.17498 270)
			(size 0.519938 1.4986)
			(layers "F.Cu" "F.Mask" "F.Paste")
			(net "GND")
		)
		(pad "86" smd rect
			(at -2.050034 14.025118 270)
			(size 0.519938 1.4986)
			(layers "F.Cu" "F.Mask" "F.Paste")
			(net "M_F_CPU0_SA_RSP<0>")
		)
		(pad "87" smd rect
			(at -2.050034 14.875002 270)
			(size 0.519938 1.4986)
			(layers "F.Cu" "F.Mask" "F.Paste")
			(net "M_F_CPU0_SB_RSP<0>")
		)
		(pad "88" smd rect
			(at -2.050034 15.724886 270)
			(size 0.519938 1.4986)
			(layers "F.Cu" "F.Mask" "F.Paste")
			(net "GND")
		)
		(pad "89" smd rect
			(at -2.050034 16.575024 270)
			(size 0.519938 1.4986)
			(layers "F.Cu" "F.Mask" "F.Paste")
			(net "M_F_CPU0_SB_CB<4>")
		)
		(pad "90" smd rect
			(at -2.050034 17.424908 270)
			(size 0.519938 1.4986)
			(layers "F.Cu" "F.Mask" "F.Paste")
			(net "GND")
		)
		(pad "91" smd rect
			(at -2.050034 18.275046 270)
			(size 0.519938 1.4986)
			(layers "F.Cu" "F.Mask" "F.Paste")
			(net "M_F_CPU0_SB_CB<5>")
		)
	)
)
